# BASEBOARD_FAB2 (Tioga Pass) — schematic netlist excerpt (pin names and nets, part order shuffled) for the footprints in the layout excerpt that follows; sources: Cadence DE-HDL packaged netlist, KiCad conversion of Wiwynn_Tioga_Pass_MB.brd

RT41  RES  0 5.0% CHIP  pkg 0603  page 214 : A = VR_PVCCIO_CPU1_PH1_BOOT ; B = VR_PVCCIO_CPU1_PH1_BOOT_R

J1F2  LOTES-CON4-S1-GP  pkg CONN-G7  page 161
  \1\  = GND
  \2\  = P12V_FAN
  \3\  = FAN_TACH0_CPU0_D1
  \4\  = FAN_PWM_OUT_SYS0_R
  NP1  = NC

(kicad_pcb
	(version 20260206)
	(generator "pcbnew")
	(generator_version "10.0")
	(general
		(thickness 1.6)
		(legacy_teardrops no)
	)
	(paper "A4")
	(title_block
		(title "Wiwynn_Tioga_Pass_MB.brd")
		(comment 1 "Tioga Pass / footprints 961-962 of 4770")
	)
	(layers
		(0 "F.Cu" signal "TOP")
		(4 "In1.Cu" signal "L2GND")
		(6 "In2.Cu" signal "L3")
		(8 "In3.Cu" signal "L4GND")
		(10 "In4.Cu" signal "L5")
		(12 "In5.Cu" signal "L6GND")
		(14 "In6.Cu" signal "L7VCC")
		(16 "In7.Cu" signal "L8VCC")
		(18 "In8.Cu" signal "L9GND")
		(20 "In9.Cu" signal "L10")
		(22 "In10.Cu" signal "L11GND")
		(24 "In11.Cu" signal "L12")
		(26 "In12.Cu" signal "L13GND")
		(2 "B.Cu" signal "BOTTOM")
		(9 "F.Adhes" user "F.Adhesive")
		(11 "B.Adhes" user "B.Adhesive")
		(13 "F.Paste" user "Package Geometry/Pastemask Top")
		(15 "B.Paste" user "Package Geometry/Pastemask Bottom")
		(5 "F.SilkS" user "Ref Des/Silkscreen Top")
		(7 "B.SilkS" user "Ref Des/Silkscreen Bottom")
		(1 "F.Mask" user "Board Geometry/Soldermask Top")
		(3 "B.Mask" user "Board Geometry/Soldermask Bottom")
		(17 "Dwgs.User" user "User.Drawings")
		(19 "Cmts.User" user "User.Comments")
		(21 "Eco1.User" user "User.Eco1")
		(23 "Eco2.User" user "User.Eco2")
		(25 "Edge.Cuts" user "Board Geometry/Outline")
		(27 "Margin" user)
		(31 "F.CrtYd" user "Package Geometry/Place Bound Top")
		(29 "B.CrtYd" user "Package Geometry/Place Bound Bottom")
		(35 "F.Fab" user "Ref Des/Assembly Top")
		(33 "B.Fab" user "Ref Des/Assembly Bottom")
	)
	(footprint ""
		(layer "F.Cu")
		(at 26.66492 -36.964874)
		(property "Reference" "J1F2"
			(at 0 0 0)
			(layer "F.SilkS")
			(hide yes)
			(effects
				(font
					(size 1.27 1.27)
				)
			)
		)
		(property "Value" "*"
			(at -6.3881 -0.97155 0)
			(unlocked yes)
			(layer "F.Fab")
			(hide yes)
			(effects
				(font
					(size 0.889 0.889)
					(thickness 0.1524)
				)
			)
		)
		(property "Device Type" "LOTES-CON4-S1-GP_CONN-G7-LOTESA"
			(at -6.3881 -2.49555 0)
			(unlocked yes)
			(layer "F.Fab")
			(hide yes)
			(effects
				(font
					(size 0.889 0.889)
					(thickness 0.1524)
				)
			)
		)
		(duplicate_pad_numbers_are_jumpers no)
		(fp_line
			(start -5.334 -3.302)
			(end 5.334 -3.302)
			(stroke
				(width 0.508)
				(type default)
			)
			(layer "F.SilkS")
		)
		(fp_line
			(start -5.334 -3.1242)
			(end 5.334 -3.1242)
			(stroke
				(width 0.1524)
				(type default)
			)
			(layer "F.SilkS")
		)
		(fp_line
			(start -5.334 3.0226)
			(end -5.334 -3.1242)
			(stroke
				(width 0.1524)
				(type default)
			)
			(layer "F.SilkS")
		)
		(fp_line
			(start 4.191 3.16484)
			(end 5.461 3.16484)
			(stroke
				(width 0.4064)
				(type default)
			)
			(layer "F.SilkS")
		)
		(fp_line
			(start 5.334 -3.1242)
			(end 5.334 3.0226)
			(stroke
				(width 0.1524)
				(type default)
			)
			(layer "F.SilkS")
		)
		(fp_line
			(start 5.334 3.0226)
			(end -5.334 3.0226)
			(stroke
				(width 0.1524)
				(type default)
			)
			(layer "F.SilkS")
		)
		(fp_line
			(start 5.461 3.16484)
			(end 5.461 1.89484)
			(stroke
				(width 0.4064)
				(type default)
			)
			(layer "F.SilkS")
		)
		(fp_circle
			(center -3.81 0)
			(end -2.5527 0)
			(stroke
				(width 0.3048)
				(type default)
			)
			(fill no)
			(layer "F.SilkS")
		)
		(fp_circle
			(center -1.27 0)
			(end -0.0127 0)
			(stroke
				(width 0.3048)
				(type default)
			)
			(fill no)
			(layer "F.SilkS")
		)
		(fp_circle
			(center 1.27 0)
			(end 2.5273 0)
			(stroke
				(width 0.3048)
				(type default)
			)
			(fill no)
			(layer "F.SilkS")
		)
		(fp_circle
			(center 3.81 0)
			(end 5.0673 0)
			(stroke
				(width 0.3048)
				(type default)
			)
			(fill no)
			(layer "F.SilkS")
		)
		(fp_rect
			(start -5.08 2.54)
			(end 5.08 -2.8702)
			(stroke
				(width 0)
				(type default)
			)
			(fill no)
			(layer "F.CrtYd")
		)
		(fp_poly
			(pts
				(xy -5.588 3.2766) (xy -5.588 -3.3782) (xy 5.588 -3.3782) (xy 5.588 -0.00635) (xy 5.08 -0.00635)
				(xy 5.08 -2.8702) (xy -5.08 -2.8702) (xy -5.08 2.54) (xy 5.08 2.54) (xy 5.08 0.00635) (xy 5.588 0.00635)
				(xy 5.588 3.2766)
			)
			(stroke
				(width 0)
				(type default)
			)
			(fill no)
			(layer "F.CrtYd")
		)
		(fp_rect
			(start -5.588 3.2766)
			(end 5.588 -3.3782)
			(stroke
				(width 0)
				(type default)
			)
			(fill no)
			(layer "F.Fab")
		)
		(pad "" np_thru_hole circle
			(at -1.27 2.189988)
			(size 0.254 0.254)
			(drill 1.1684)
			(layers "*.Cu" "*.Mask")
			(clearance 0.8128)
			(thermal_gap 0.8128)
		)
		(pad "1" thru_hole circle
			(at 3.81 0)
			(size 1.8034 1.8034)
			(drill 1.1684)
			(layers "*.Cu" "*.Mask")
			(remove_unused_layers no)
			(net "GND")
			(clearance 0.1905)
			(thermal_gap 0.1905)
		)
		(pad "2" thru_hole circle
			(at 1.27 0)
			(size 1.8034 1.8034)
			(drill 1.1684)
			(layers "*.Cu" "*.Mask")
			(remove_unused_layers no)
			(net "P12V_FAN")
			(clearance 0.1905)
			(thermal_gap 0.1905)
		)
		(pad "3" thru_hole circle
			(at -1.27 0)
			(size 1.8034 1.8034)
			(drill 1.1684)
			(layers "*.Cu" "*.Mask")
			(remove_unused_layers no)
			(net "FAN_TACH0_CPU0_D1")
			(clearance 0.1905)
			(thermal_gap 0.1905)
		)
		(pad "4" thru_hole circle
			(at -3.81 0)
			(size 1.8034 1.8034)
			(drill 1.1684)
			(layers "*.Cu" "*.Mask")
			(remove_unused_layers no)
			(net "FAN_PWM_OUT_SYS0_R")
			(clearance 0.1905)
			(thermal_gap 0.1905)
		)
		(zone
			(layers "F.Cu" "B.Cu" "In1.Cu" "In2.Cu" "In3.Cu" "In4.Cu" "In5.Cu" "In6.Cu"
				"In7.Cu" "In8.Cu" "In9.Cu" "In10.Cu" "In11.Cu" "In12.Cu"
			)
			(hatch none 0.5)
			(connect_pads
				(clearance 0)
			)
			(min_thickness 0.25)
			(keepout
				(tracks not_allowed)
				(vias allowed)
				(pads allowed)
				(copperpour not_allowed)
				(footprints allowed)
			)
			(placement
				(enabled no)
				(sheetname "")
			)
			(fill
				(thermal_gap 0.5)
				(thermal_bridge_width 0.5)
				(island_removal_mode 0)
			)
			(polygon
				(pts
					(arc
						(start 26.28392 -34.774886)
						(mid 24.50592 -34.774886)
						(end 26.28392 -34.774886)
					)
				)
			)
		)
	)
	(footprint ""
		(layer "F.Cu")
		(at 183.769 -53.594 -90)
		(property "Reference" "RT41"
			(at 1.01473 0.656336 180)
			(unlocked yes)
			(layer "F.SilkS")
			(effects
				(font
					(size 0.4064 0.254)
					(thickness 0.1524)
				)
			)
		)
		(property "Value" ""
			(at 0 0 270)
			(layer "F.Fab")
			(effects
				(font
					(size 1.27 1.27)
				)
			)
		)
		(duplicate_pad_numbers_are_jumpers no)
		(fp_poly
			(pts
				(xy -0.4953 -0.2032) (xy 0.4953 -0.2032) (xy 0.4953 1.6002) (xy -0.4953 1.6002)
			)
			(stroke
				(width 0)
				(type default)
			)
			(fill no)
			(layer "F.CrtYd")
		)
		(fp_line
			(start -0.4953 1.6002)
			(end -0.4953 -0.2032)
			(stroke
				(width 0.1)
				(type default)
			)
			(layer "F.Fab")
		)
		(fp_line
			(start 0.4953 1.6002)
			(end -0.4953 1.6002)
			(stroke
				(width 0.1)
				(type default)
			)
			(layer "F.Fab")
		)
		(fp_line
			(start -0.4953 -0.2032)
			(end 0.4953 -0.2032)
			(stroke
				(width 0.1)
				(type default)
			)
			(layer "F.Fab")
		)
		(fp_line
			(start 0.4953 -0.2032)
			(end 0.4953 1.6002)
			(stroke
				(width 0.1)
				(type default)
			)
			(layer "F.Fab")
		)
		(pad "1" smd rect
			(at 0 0 270)
			(size 0.762 0.889)
			(layers "F.Cu" "F.Mask" "F.Paste")
			(net "VR_PVCCIO_CPU1_PH1_BOOT")
		)
		(pad "2" smd rect
			(at 0 1.397 270)
			(size 0.762 0.889)
			(layers "F.Cu" "F.Mask" "F.Paste")
			(net "VR_PVCCIO_CPU1_PH1_BOOT_R")
		)
		(zone
			(layer "F.Cu")
			(hatch none 0.5)
			(connect_pads
				(clearance 0)
			)
			(min_thickness 0.25)
			(keepout
				(tracks not_allowed)
				(vias allowed)
				(pads allowed)
				(copperpour not_allowed)
				(footprints allowed)
			)
			(placement
				(enabled no)
				(sheetname "")
			)
			(fill
				(thermal_gap 0.5)
				(thermal_bridge_width 0.5)
				(island_removal_mode 0)
			)
			(polygon
				(pts
					(xy 182.8165 -53.975) (xy 182.8165 -53.213) (xy 183.3245 -53.213) (xy 183.3245 -53.975)
				)
			)
		)
		(zone
			(layer "F.Cu")
			(hatch none 0.5)
			(connect_pads
				(clearance 0)
			)
			(min_thickness 0.25)
			(keepout
				(tracks allowed)
				(vias not_allowed)
				(pads allowed)
				(copperpour not_allowed)
				(footprints allowed)
			)
			(placement
				(enabled no)
				(sheetname "")
			)
			(fill
				(thermal_gap 0.5)
				(thermal_bridge_width 0.5)
				(island_removal_mode 0)
			)
			(polygon
				(pts
					(xy 182.8165 -53.213) (xy 183.3245 -53.213) (xy 183.3245 -53.975) (xy 182.8165 -53.975)
				)
			)
		)
	)
)
